# S9S_MB_2U (Grand Teton) — schematic netlist excerpt (pin names and nets, part order shuffled) for the footprints in the layout excerpt that follows; sources: Cadence DE-HDL packaged netlist, KiCad conversion of 03242023_DA0F0TMBIJ0_F0T_Motherboard_J_brd_V01_OCP.brd

C826  Q_CAP_DIFFBUS  DIFF BUS_0.22UF 6.3V 20% X6S  pkg C0201  page 175 : \1\ = P5E_CPU1_PE1_TX_C_DN<5> ; \2\ = P5E_CPU1_PE1_TX_DN<5>

U212  74LVC2G07DW7  74LVC2G07DW-7 IC  pkg SOT363_0-65_2X1-25XC  page 156
  \1a\  = OCP_SFF_PRSNT2_R_N
  GND  = GND
  \2a\  = OCP_SFF_PRSNT3_R_N
  \2y\  = HP_LVC3_OCP_V3_1_PRSNT2_N_R
  VCC  = P3V3_AUX
  \1y\  = HP_LVC3_OCP_V3_1_PRSNT2_N_R

(kicad_pcb
	(version 20260206)
	(generator "pcbnew")
	(generator_version "10.0")
	(general
		(thickness 1.6)
		(legacy_teardrops no)
	)
	(paper "A4")
	(title_block
		(title "03242023_DA0F0TMBIJ0_F0T_Motherboard_J_brd_V01_OCP.brd")
		(comment 1 "Grand Teton / footprints 3587-3588 of 6105")
	)
	(layers
		(0 "F.Cu" signal "TOP")
		(4 "In1.Cu" signal "GND")
		(6 "In2.Cu" signal "IN1")
		(8 "In3.Cu" signal "GND1")
		(10 "In4.Cu" signal "IN2")
		(12 "In5.Cu" signal "GND2")
		(14 "In6.Cu" signal "IN3")
		(16 "In7.Cu" signal "GND3")
		(18 "In8.Cu" signal "VCC")
		(20 "In9.Cu" signal "VCC1")
		(22 "In10.Cu" signal "GND4")
		(24 "In11.Cu" signal "IN4")
		(26 "In12.Cu" signal "GND5")
		(28 "In13.Cu" signal "IN5")
		(30 "In14.Cu" signal "GND6")
		(32 "In15.Cu" signal "IN6")
		(34 "In16.Cu" signal "GND7")
		(2 "B.Cu" signal "BOTTOM")
		(9 "F.Adhes" user "F.Adhesive")
		(11 "B.Adhes" user "B.Adhesive")
		(13 "F.Paste" user "Package Geometry/Pastemask Top")
		(15 "B.Paste" user "Package Geometry/Pastemask Bottom")
		(5 "F.SilkS" user "Ref Des/Silkscreen Top")
		(7 "B.SilkS" user "Ref Des/Silkscreen Bottom")
		(1 "F.Mask" user "Board Geometry/Soldermask Top")
		(3 "B.Mask" user "Board Geometry/Soldermask Bottom")
		(17 "Dwgs.User" user "User.Drawings")
		(19 "Cmts.User" user "User.Comments")
		(21 "Eco1.User" user "User.Eco1")
		(23 "Eco2.User" user "User.Eco2")
		(25 "Edge.Cuts" user "Board Geometry/Outline")
		(27 "Margin" user)
		(31 "F.CrtYd" user "Package Geometry/Place Bound Top")
		(29 "B.CrtYd" user "Package Geometry/Place Bound Bottom")
		(35 "F.Fab" user "Ref Des/Assembly Top")
		(33 "B.Fab" user "Ref Des/Assembly Bottom")
	)
	(footprint ""
		(layer "F.Cu")
		(at 44.668694 -16.099536 90)
		(property "Reference" "C826"
			(at 0 0 90)
			(layer "F.SilkS")
			(hide yes)
			(effects
				(font
					(size 1.27 1.27)
				)
			)
		)
		(property "Value" ""
			(at 0 0 90)
			(layer "F.Fab")
			(effects
				(font
					(size 1.27 1.27)
				)
			)
		)
		(duplicate_pad_numbers_are_jumpers no)
		(fp_line
			(start 0.299974 -0.150114)
			(end 0.299974 0.150114)
			(stroke
				(width 0.1)
				(type default)
			)
			(layer "F.Fab")
		)
		(fp_line
			(start -0.299974 -0.150114)
			(end 0.299974 -0.150114)
			(stroke
				(width 0.1)
				(type default)
			)
			(layer "F.Fab")
		)
		(fp_line
			(start 0.299974 0.150114)
			(end -0.299974 0.150114)
			(stroke
				(width 0.1)
				(type default)
			)
			(layer "F.Fab")
		)
		(fp_line
			(start -0.299974 0.150114)
			(end -0.299974 -0.150114)
			(stroke
				(width 0.1)
				(type default)
			)
			(layer "F.Fab")
		)
		(pad "1" smd rect
			(at -0.2667 0 90)
			(size 0.3048 0.381)
			(layers "F.Cu" "F.Mask" "F.Paste")
			(net "P5E_CPU1_PE1_TX_C_DN<5>")
		)
		(pad "2" smd rect
			(at 0.2667 0 90)
			(size 0.3048 0.381)
			(layers "F.Cu" "F.Mask" "F.Paste")
			(net "P5E_CPU1_PE1_TX_DN<5>")
		)
	)
	(footprint ""
		(layer "F.Cu")
		(at 457.687426 -103.646224)
		(property "Reference" "U212"
			(at -1.490726 -1.641094 0)
			(unlocked yes)
			(layer "F.SilkS")
			(effects
				(font
					(size 0.7874 0.5842)
					(thickness 0.1524)
				)
				(justify left)
			)
		)
		(property "Value" ""
			(at 0 0 0)
			(layer "F.Fab")
			(effects
				(font
					(size 1.27 1.27)
				)
			)
		)
		(duplicate_pad_numbers_are_jumpers no)
		(fp_line
			(start -1.38176 -1.100074)
			(end -1.38176 1.100074)
			(stroke
				(width 0.1524)
				(type default)
			)
			(layer "F.SilkS")
		)
		(fp_line
			(start -1.38176 1.100074)
			(end 1.38176 1.100074)
			(stroke
				(width 0.1524)
				(type default)
			)
			(layer "F.SilkS")
		)
		(fp_line
			(start -0.592074 -1.100074)
			(end -1.38176 -1.100074)
			(stroke
				(width 0.1524)
				(type default)
			)
			(layer "F.SilkS")
		)
		(fp_line
			(start 0 -0.508)
			(end -0.592074 -1.100074)
			(stroke
				(width 0.1524)
				(type default)
			)
			(layer "F.SilkS")
		)
		(fp_line
			(start 0.592074 -1.100074)
			(end 0 -0.508)
			(stroke
				(width 0.1524)
				(type default)
			)
			(layer "F.SilkS")
		)
		(fp_line
			(start 1.38176 -1.100074)
			(end 0.592074 -1.100074)
			(stroke
				(width 0.1524)
				(type default)
			)
			(layer "F.SilkS")
		)
		(fp_line
			(start 1.38176 1.100074)
			(end 1.38176 -1.100074)
			(stroke
				(width 0.1524)
				(type default)
			)
			(layer "F.SilkS")
		)
		(fp_poly
			(pts
				(xy -1.50241 -0.649986) (xy -1.9431 -0.429768) (xy -1.9431 -0.870204)
			)
			(stroke
				(width 0)
				(type default)
			)
			(fill yes)
			(layer "F.SilkS")
		)
		(fp_line
			(start -0.674878 -1.100074)
			(end -0.674878 1.100074)
			(stroke
				(width 0.1)
				(type default)
			)
			(layer "F.Fab")
		)
		(fp_line
			(start -0.674878 1.100074)
			(end 0.674878 1.100074)
			(stroke
				(width 0.1)
				(type default)
			)
			(layer "F.Fab")
		)
		(fp_line
			(start 0.674878 -1.100074)
			(end -0.674878 -1.100074)
			(stroke
				(width 0.1)
				(type default)
			)
			(layer "F.Fab")
		)
		(fp_line
			(start 0.674878 1.100074)
			(end 0.674878 -1.100074)
			(stroke
				(width 0.1)
				(type default)
			)
			(layer "F.Fab")
		)
		(fp_poly
			(pts
				(xy -1.9431 -0.870204) (xy -1.50241 -0.649986) (xy -1.9431 -0.429768)
			)
			(stroke
				(width 0)
				(type default)
			)
			(fill yes)
			(layer "F.Fab")
		)
		(pad "1" smd rect
			(at -0.94996 -0.649986 270)
			(size 0.4318 0.6096)
			(layers "F.Cu" "F.Mask" "F.Paste")
			(net "OCP_SFF_PRSNT2_R_N")
		)
		(pad "2" smd rect
			(at -0.94996 0 270)
			(size 0.4318 0.6096)
			(layers "F.Cu" "F.Mask" "F.Paste")
			(net "GND")
		)
		(pad "3" smd rect
			(at -0.94996 0.649986 270)
			(size 0.4318 0.6096)
			(layers "F.Cu" "F.Mask" "F.Paste")
			(net "OCP_SFF_PRSNT3_R_N")
		)
		(pad "4" smd rect
			(at 0.94996 0.649986 270)
			(size 0.4318 0.6096)
			(layers "F.Cu" "F.Mask" "F.Paste")
			(net "HP_LVC3_OCP_V3_1_PRSNT2_N_R")
		)
		(pad "5" smd rect
			(at 0.94996 0 270)
			(size 0.4318 0.6096)
			(layers "F.Cu" "F.Mask" "F.Paste")
			(net "P3V3_AUX")
		)
		(pad "6" smd rect
			(at 0.94996 -0.649986 270)
			(size 0.4318 0.6096)
			(layers "F.Cu" "F.Mask" "F.Paste")
			(net "HP_LVC3_OCP_V3_1_PRSNT2_N_R")
		)
	)
)
